(kicad_pcb
	(version 20241229)
	(generator "pcbnew")
	(generator_version "9.0")
	(general
		(thickness 1.61)
		(legacy_teardrops no)
	)
	(paper "A3")
	(title_block
		(title "SO-DIMM DDR5 Tester")
		(date "2025-11-26")
		(rev "1.3.0")
		(comment 9 "footprints 376-381 of 627")
	)
	(layers
		(0 "F.Cu" signal)
		(4 "In1.Cu" power)
		(6 "In2.Cu" mixed)
		(8 "In3.Cu" power)
		(10 "In4.Cu" mixed)
		(12 "In5.Cu" power)
		(14 "In6.Cu" mixed)
		(16 "In7.Cu" power)
		(18 "In8.Cu" power)
		(20 "In9.Cu" mixed)
		(22 "In10.Cu" power)
		(2 "B.Cu" signal)
		(9 "F.Adhes" user "F.Adhesive")
		(11 "B.Adhes" user "B.Adhesive")
		(13 "F.Paste" user)
		(15 "B.Paste" user)
		(5 "F.SilkS" user "F.Silkscreen")
		(7 "B.SilkS" user "B.Silkscreen")
		(1 "F.Mask" user)
		(3 "B.Mask" user)
		(17 "Dwgs.User" user "User.Drawings")
		(19 "Cmts.User" user "User.Comments")
		(21 "Eco1.User" user "User.Eco1")
		(23 "Eco2.User" user "User.Eco2")
		(25 "Edge.Cuts" user)
		(27 "Margin" user)
		(31 "F.CrtYd" user "F.Courtyard")
		(29 "B.CrtYd" user "B.Courtyard")
		(35 "F.Fab" user)
		(33 "B.Fab" user)
	)
	(footprint "antmicro-footprints:C_0402_1005Metric"
		(layer "B.Cu")
		(at 149.875001 180.300501 180)
		(descr "Capacitor SMD 0402 (1005 Metric), square (rectangular) end terminal, IPC_7351 nominal, (Body size source: IPC-SM-782 page 76, https://www.pcb-3d.com/wordpress/wp-content/uploads/ipc-sm-782a_amendment_1_and_2.pdf)")
		(tags "capacitor 0402")
		(property "Reference" "C107"
			(at 0 1.17 0)
			(layer "B.SilkS")
			(hide yes)
			(effects
				(font
					(size 0.7 0.7)
					(thickness 0.15)
				)
				(justify left bottom mirror)
			)
		)
		(property "Value" "C_100n_0402"
			(at 0 -1.169 0)
			(layer "B.Fab")
			(effects
				(font
					(size 0.7 0.7)
					(thickness 0.15)
				)
				(justify left bottom mirror)
			)
		)
		(property "Datasheet" "https://www.murata.com/products/productdetail?partno=GRM155R61H104KE14%23"
			(at 0 0 180)
			(layer "F.Fab")
			(hide yes)
			(effects
				(font
					(size 1.27 1.27)
					(thickness 0.15)
				)
			)
		)
		(property "Author" "Antmicro"
			(at 299.750002 360.601002 0)
			(layer "B.Fab")
			(hide yes)
			(effects
				(font
					(size 1 1)
					(thickness 0.15)
				)
				(justify mirror)
			)
		)
		(property "Dielectric" "X5R"
			(at 299.750002 360.601002 0)
			(layer "B.Fab")
			(hide yes)
			(effects
				(font
					(size 1 1)
					(thickness 0.15)
				)
				(justify mirror)
			)
		)
		(property "License" "Apache-2.0"
			(at 299.750002 360.601002 0)
			(layer "B.Fab")
			(hide yes)
			(effects
				(font
					(size 1 1)
					(thickness 0.15)
				)
				(justify mirror)
			)
		)
		(property "MPN" "GRM155R61H104KE14D"
			(at 299.750002 360.601002 0)
			(layer "B.Fab")
			(hide yes)
			(effects
				(font
					(size 1 1)
					(thickness 0.15)
				)
				(justify mirror)
			)
		)
		(property "Manufacturer" "Murata"
			(at 299.750002 360.601002 0)
			(layer "B.Fab")
			(hide yes)
			(effects
				(font
					(size 1 1)
					(thickness 0.15)
				)
				(justify mirror)
			)
		)
		(property "Val" "100n"
			(at 299.750002 360.601002 0)
			(layer "B.Fab")
			(hide yes)
			(effects
				(font
					(size 1 1)
					(thickness 0.15)
				)
				(justify mirror)
			)
		)
		(property "Voltage" "50V"
			(at 299.750002 360.601002 0)
			(layer "B.Fab")
			(hide yes)
			(effects
				(font
					(size 1 1)
					(thickness 0.15)
				)
				(justify mirror)
			)
		)
		(sheetname "/FPGA power/")
		(sheetfile "fpga-power.kicad_sch")
		(attr smd)
		(fp_rect
			(start -0.9656 0.4572)
			(end 0.9652 -0.4828)
			(stroke
				(width 0.05)
				(type solid)
			)
			(fill no)
			(layer "B.CrtYd")
		)
		(fp_line
			(start 0.498 0.25)
			(end 0.498 -0.248)
			(stroke
				(width 0.15)
				(type solid)
			)
			(layer "B.Fab")
		)
		(fp_line
			(start 0.498 -0.248)
			(end -0.5 -0.248)
			(stroke
				(width 0.15)
				(type solid)
			)
			(layer "B.Fab")
		)
		(fp_line
			(start -0.5 0.25)
			(end 0.498 0.25)
			(stroke
				(width 0.15)
				(type solid)
			)
			(layer "B.Fab")
		)
		(fp_line
			(start -0.5 -0.248)
			(end -0.5 0.25)
			(stroke
				(width 0.15)
				(type solid)
			)
			(layer "B.Fab")
		)
		(pad "1" smd roundrect
			(at -0.5 0 90)
			(size 0.6 0.6)
			(layers "B.Cu" "B.Mask" "B.Paste")
			(roundrect_rratio 0.25)
			(net 1 "GND")
			(pintype "passive")
		)
		(pad "2" smd roundrect
			(at 0.498 0 180)
			(size 0.6 0.6)
			(layers "B.Cu" "B.Mask" "B.Paste")
			(roundrect_rratio 0.25)
			(net 226 "+1V2_MGTAVTT")
			(pintype "passive")
		)
	)
	(footprint "antmicro-footprints:C_0402_1005Metric"
		(layer "B.Cu")
		(at 99.270501 138.236 180)
		(descr "Capacitor SMD 0402")
		(tags "capacitor SMD 0402")
		(property "Reference" "C166"
			(at 0 0.699 0)
			(layer "B.SilkS")
			(hide yes)
			(effects
				(font
					(size 0.7 0.7)
					(thickness 0.15)
				)
				(justify left bottom mirror)
			)
		)
		(property "Value" "C_100n_0402"
			(at -1.022927 -2.155213 0)
			(layer "B.Fab")
			(effects
				(font
					(size 0.7 0.7)
					(thickness 0.15)
				)
				(justify left bottom mirror)
			)
		)
		(property "Datasheet" "https://www.murata.com/products/productdetail?partno=GRM155R61H104KE14%23"
			(at 0 0 180)
			(layer "F.Fab")
			(hide yes)
			(effects
				(font
					(size 1.27 1.27)
					(thickness 0.15)
				)
			)
		)
		(property "Author" "Antmicro"
			(at 198.541002 276.472 0)
			(layer "B.Fab")
			(hide yes)
			(effects
				(font
					(size 1 1)
					(thickness 0.15)
				)
				(justify mirror)
			)
		)
		(property "Dielectric" "X5R"
			(at 198.541002 276.472 0)
			(layer "B.Fab")
			(hide yes)
			(effects
				(font
					(size 1 1)
					(thickness 0.15)
				)
				(justify mirror)
			)
		)
		(property "License" "Apache-2.0"
			(at 198.541002 276.472 0)
			(layer "B.Fab")
			(hide yes)
			(effects
				(font
					(size 1 1)
					(thickness 0.15)
				)
				(justify mirror)
			)
		)
		(property "MPN" "GRM155R61H104KE14D"
			(at 198.541002 276.472 0)
			(layer "B.Fab")
			(hide yes)
			(effects
				(font
					(size 1 1)
					(thickness 0.15)
				)
				(justify mirror)
			)
		)
		(property "Manufacturer" "Murata"
			(at 198.541002 276.472 0)
			(layer "B.Fab")
			(hide yes)
			(effects
				(font
					(size 1 1)
					(thickness 0.15)
				)
				(justify mirror)
			)
		)
		(property "Val" "100n"
			(at 198.541002 276.472 0)
			(layer "B.Fab")
			(hide yes)
			(effects
				(font
					(size 1 1)
					(thickness 0.15)
				)
				(justify mirror)
			)
		)
		(property "Voltage" "50V"
			(at 198.541002 276.472 0)
			(layer "B.Fab")
			(hide yes)
			(effects
				(font
					(size 1 1)
					(thickness 0.15)
				)
				(justify mirror)
			)
		)
		(sheetname "/I^{2}C/")
		(sheetfile "i2c.kicad_sch")
		(attr smd)
		(fp_rect
			(start -0.9659 0.481258)
			(end 0.9649 -0.458742)
			(stroke
				(width 0.05)
				(type solid)
			)
			(fill no)
			(layer "B.CrtYd")
		)
		(fp_line
			(start 0.499 0.25)
			(end 0.499 -0.248)
			(stroke
				(width 0.15)
				(type solid)
			)
			(layer "B.Fab")
		)
		(fp_line
			(start 0.499 -0.248)
			(end -0.499 -0.248)
			(stroke
				(width 0.15)
				(type solid)
			)
			(layer "B.Fab")
		)
		(fp_line
			(start -0.499 0.25)
			(end 0.499 0.25)
			(stroke
				(width 0.15)
				(type solid)
			)
			(layer "B.Fab")
		)
		(fp_line
			(start -0.499 -0.248)
			(end -0.499 0.25)
			(stroke
				(width 0.15)
				(type solid)
			)
			(layer "B.Fab")
		)
		(pad "1" smd roundrect
			(at -0.484 0 180)
			(size 0.59 0.64)
			(layers "B.Cu" "B.Mask" "B.Paste")
			(roundrect_rratio 0.25)
			(net 267 "VDDSPD")
			(pintype "passive")
		)
		(pad "2" smd roundrect
			(at 0.484 0 180)
			(size 0.59 0.64)
			(layers "B.Cu" "B.Mask" "B.Paste")
			(roundrect_rratio 0.25)
			(net 1 "GND")
			(pintype "passive")
		)
	)
	(footprint "antmicro-footprints:R_0402_1005Metric"
		(layer "B.Cu")
		(at 180.8 194.05 180)
		(descr "Resistor SMD 0402")
		(tags "resistor SMD 0402")
		(property "Reference" "R159"
			(at 1.25 -0.4 0)
			(layer "B.SilkS")
			(effects
				(font
					(size 0.7 0.7)
					(thickness 0.15)
				)
				(justify left bottom mirror)
			)
		)
		(property "Value" "R_4k7_0402"
			(at -1.011843 -1.772047 0)
			(layer "B.Fab")
			(effects
				(font
					(size 0.7 0.7)
					(thickness 0.15)
				)
				(justify left bottom mirror)
			)
		)
		(property "Datasheet" "https://www.bourns.com/docs/product-datasheets/cr.pdf"
			(at 0 0 180)
			(layer "F.Fab")
			(hide yes)
			(effects
				(font
					(size 1.27 1.27)
					(thickness 0.15)
				)
			)
		)
		(property "Author" "Antmicro"
			(at 361.6 388.1 0)
			(layer "B.Fab")
			(hide yes)
			(effects
				(font
					(size 1 1)
					(thickness 0.15)
				)
				(justify mirror)
			)
		)
		(property "License" "Apache-2.0"
			(at 361.6 388.1 0)
			(layer "B.Fab")
			(hide yes)
			(effects
				(font
					(size 1 1)
					(thickness 0.15)
				)
				(justify mirror)
			)
		)
		(property "MPN" "CR0402-FX-4701GLF"
			(at 361.6 388.1 0)
			(layer "B.Fab")
			(hide yes)
			(effects
				(font
					(size 1 1)
					(thickness 0.15)
				)
				(justify mirror)
			)
		)
		(property "Manufacturer" "Bourns"
			(at 361.6 388.1 0)
			(layer "B.Fab")
			(hide yes)
			(effects
				(font
					(size 1 1)
					(thickness 0.15)
				)
				(justify mirror)
			)
		)
		(property "Tolerance" "1%"
			(at 361.6 388.1 0)
			(layer "B.Fab")
			(hide yes)
			(effects
				(font
					(size 1 1)
					(thickness 0.15)
				)
				(justify mirror)
			)
		)
		(property "Val" "4k7"
			(at 361.6 388.1 0)
			(layer "B.Fab")
			(hide yes)
			(effects
				(font
					(size 1 1)
					(thickness 0.15)
				)
				(justify mirror)
			)
		)
		(sheetname "/I^{2}C/")
		(sheetfile "i2c.kicad_sch")
		(attr smd)
		(fp_rect
			(start -0.93 0.47)
			(end 0.93 -0.47)
			(stroke
				(width 0.05)
				(type solid)
			)
			(fill no)
			(layer "B.CrtYd")
		)
		(fp_rect
			(start -0.5 0.25)
			(end 0.5 -0.25)
			(stroke
				(width 0.15)
				(type solid)
			)
			(fill no)
			(layer "B.Fab")
		)
		(pad "1" smd roundrect
			(at -0.485 0 180)
			(size 0.59 0.64)
			(layers "B.Cu" "B.Mask" "B.Paste")
			(roundrect_rratio 0.25)
			(net 200 "+3V3")
			(pintype "passive")
		)
		(pad "2" smd roundrect
			(at 0.485 0 180)
			(size 0.59 0.64)
			(layers "B.Cu" "B.Mask" "B.Paste")
			(roundrect_rratio 0.25)
			(net 689 "/FPGA bank 14/FPGA_PWR.SCL")
			(pintype "passive")
		)
	)
	(footprint "antmicro-footprints:R_0402_1005Metric"
		(layer "B.Cu")
		(at 196.950001 151.8 180)
		(descr "Resistor SMD 0402")
		(tags "resistor SMD 0402")
		(property "Reference" "R139"
			(at -1.122484 0.772697 0)
			(layer "B.SilkS")
			(hide yes)
			(effects
				(font
					(size 0.7 0.7)
					(thickness 0.15)
				)
				(justify left bottom mirror)
			)
		)
		(property "Value" "R_47k_0402"
			(at -1.011843 -1.772047 0)
			(layer "B.Fab")
			(effects
				(font
					(size 0.7 0.7)
					(thickness 0.15)
				)
				(justify left bottom mirror)
			)
		)
		(property "Datasheet" "https://www.bourns.com/docs/product-datasheets/cr.pdf"
			(at 0 0 180)
			(layer "F.Fab")
			(hide yes)
			(effects
				(font
					(size 1.27 1.27)
					(thickness 0.15)
				)
			)
		)
		(property "Author" "Antmicro"
			(at 393.900002 303.6 0)
			(layer "B.Fab")
			(hide yes)
			(effects
				(font
					(size 1 1)
					(thickness 0.15)
				)
				(justify mirror)
			)
		)
		(property "License" "Apache-2.0"
			(at 393.900002 303.6 0)
			(layer "B.Fab")
			(hide yes)
			(effects
				(font
					(size 1 1)
					(thickness 0.15)
				)
				(justify mirror)
			)
		)
		(property "MPN" "CR0402-FX-4702GLF"
			(at 393.900002 303.6 0)
			(layer "B.Fab")
			(hide yes)
			(effects
				(font
					(size 1 1)
					(thickness 0.15)
				)
				(justify mirror)
			)
		)
		(property "Manufacturer" "Bourns"
			(at 393.900002 303.6 0)
			(layer "B.Fab")
			(hide yes)
			(effects
				(font
					(size 1 1)
					(thickness 0.15)
				)
				(justify mirror)
			)
		)
		(property "Tolerance" "1%"
			(at 393.900002 303.6 0)
			(layer "B.Fab")
			(hide yes)
			(effects
				(font
					(size 1 1)
					(thickness 0.15)
				)
				(justify mirror)
			)
		)
		(property "Val" "47k"
			(at 393.900002 303.6 0)
			(layer "B.Fab")
			(hide yes)
			(effects
				(font
					(size 1 1)
					(thickness 0.15)
				)
				(justify mirror)
			)
		)
		(sheetname "/Supply/")
		(sheetfile "supply.kicad_sch")
		(attr smd)
		(fp_rect
			(start -0.93 0.47)
			(end 0.93 -0.47)
			(stroke
				(width 0.05)
				(type solid)
			)
			(fill no)
			(layer "B.CrtYd")
		)
		(fp_rect
			(start -0.5 0.25)
			(end 0.5 -0.25)
			(stroke
				(width 0.15)
				(type solid)
			)
			(fill no)
			(layer "B.Fab")
		)
		(pad "1" smd roundrect
			(at -0.485 0 180)
			(size 0.59 0.64)
			(layers "B.Cu" "B.Mask" "B.Paste")
			(roundrect_rratio 0.25)
			(net 686 "IN1")
			(pintype "passive")
		)
		(pad "2" smd roundrect
			(at 0.485 0 180)
			(size 0.59 0.64)
			(layers "B.Cu" "B.Mask" "B.Paste")
			(roundrect_rratio 0.25)
			(net 41 "+3V3_AON")
			(pintype "passive")
		)
	)
	(footprint "antmicro-footprints:C_0402_1005Metric"
		(layer "B.Cu")
		(at 141.875001 171.3025 180)
		(descr "Capacitor SMD 0402 (1005 Metric), square (rectangular) end terminal, IPC_7351 nominal, (Body size source: IPC-SM-782 page 76, https://www.pcb-3d.com/wordpress/wp-content/uploads/ipc-sm-782a_amendment_1_and_2.pdf)")
		(tags "capacitor 0402")
		(property "Reference" "C34"
			(at 0 1.17 0)
			(layer "B.SilkS")
			(hide yes)
			(effects
				(font
					(size 0.7 0.7)
					(thickness 0.15)
				)
				(justify left bottom mirror)
			)
		)
		(property "Value" "C_4u7_0402"
			(at 0 -1.169 0)
			(layer "B.Fab")
			(effects
				(font
					(size 0.7 0.7)
					(thickness 0.15)
				)
				(justify left bottom mirror)
			)
		)
		(property "Datasheet" "https://www.murata.com/products/productdetail?partno=GRM155R61A475MEAA%23"
			(at 0 0 180)
			(layer "F.Fab")
			(hide yes)
			(effects
				(font
					(size 1.27 1.27)
					(thickness 0.15)
				)
			)
		)
		(property "Author" "Antmicro"
			(at 283.750002 342.605 0)
			(layer "B.Fab")
			(hide yes)
			(effects
				(font
					(size 1 1)
					(thickness 0.15)
				)
				(justify mirror)
			)
		)
		(property "Dielectric" ""
			(at 283.750002 342.605 0)
			(layer "B.Fab")
			(hide yes)
			(effects
				(font
					(size 1 1)
					(thickness 0.15)
				)
				(justify mirror)
			)
		)
		(property "License" "Apache-2.0"
			(at 283.750002 342.605 0)
			(layer "B.Fab")
			(hide yes)
			(effects
				(font
					(size 1 1)
					(thickness 0.15)
				)
				(justify mirror)
			)
		)
		(property "MPN" "GRM155R61A475MEAAD"
			(at 283.750002 342.605 0)
			(layer "B.Fab")
			(hide yes)
			(effects
				(font
					(size 1 1)
					(thickness 0.15)
				)
				(justify mirror)
			)
		)
		(property "Manufacturer" "Murata"
			(at 283.750002 342.605 0)
			(layer "B.Fab")
			(hide yes)
			(effects
				(font
					(size 1 1)
					(thickness 0.15)
				)
				(justify mirror)
			)
		)
		(property "Val" "4u7"
			(at 283.750002 342.605 0)
			(layer "B.Fab")
			(hide yes)
			(effects
				(font
					(size 1 1)
					(thickness 0.15)
				)
				(justify mirror)
			)
		)
		(property "Voltage" ""
			(at 283.750002 342.605 0)
			(layer "B.Fab")
			(hide yes)
			(effects
				(font
					(size 1 1)
					(thickness 0.15)
				)
				(justify mirror)
			)
		)
		(sheetname "/FPGA power/")
		(sheetfile "fpga-power.kicad_sch")
		(attr smd)
		(fp_rect
			(start -0.9656 0.4572)
			(end 0.9652 -0.4828)
			(stroke
				(width 0.05)
				(type solid)
			)
			(fill no)
			(layer "B.CrtYd")
		)
		(fp_line
			(start 0.498 0.25)
			(end 0.498 -0.248)
			(stroke
				(width 0.15)
				(type solid)
			)
			(layer "B.Fab")
		)
		(fp_line
			(start 0.498 -0.248)
			(end -0.5 -0.248)
			(stroke
				(width 0.15)
				(type solid)
			)
			(layer "B.Fab")
		)
		(fp_line
			(start -0.5 0.25)
			(end 0.498 0.25)
			(stroke
				(width 0.15)
				(type solid)
			)
			(layer "B.Fab")
		)
		(fp_line
			(start -0.5 -0.248)
			(end -0.5 0.25)
			(stroke
				(width 0.15)
				(type solid)
			)
			(layer "B.Fab")
		)
		(pad "1" smd roundrect
			(at -0.5 0 90)
			(size 0.6 0.6)
			(layers "B.Cu" "B.Mask" "B.Paste")
			(roundrect_rratio 0.25)
			(net 188 "+1V8")
			(pintype "passive")
		)
		(pad "2" smd roundrect
			(at 0.498 0 180)
			(size 0.6 0.6)
			(layers "B.Cu" "B.Mask" "B.Paste")
			(roundrect_rratio 0.25)
			(net 1 "GND")
			(pintype "passive")
		)
	)
	(footprint "antmicro-footprints:C_0402_1005Metric"
		(layer "B.Cu")
		(at 136.525501 204.850501 90)
		(descr "Capacitor SMD 0402")
		(tags "capacitor SMD 0402")
		(property "Reference" "C228"
			(at 0 0.699 270)
			(layer "B.SilkS")
			(hide yes)
			(effects
				(font
					(size 0.7 0.7)
					(thickness 0.15)
				)
				(justify left bottom mirror)
			)
		)
		(property "Value" "C_100n_0402"
			(at -1.022927 -2.155213 270)
			(layer "B.Fab")
			(effects
				(font
					(size 0.7 0.7)
					(thickness 0.15)
				)
				(justify left bottom mirror)
			)
		)
		(property "Datasheet" "https://www.murata.com/products/productdetail?partno=GRM155R61H104KE14%23"
			(at 0 0 90)
			(layer "F.Fab")
			(hide yes)
			(effects
				(font
					(size 1.27 1.27)
					(thickness 0.15)
				)
			)
		)
		(property "Author" "Antmicro"
			(at 341.376002 68.325 0)
			(layer "B.Fab")
			(hide yes)
			(effects
				(font
					(size 1 1)
					(thickness 0.15)
				)
				(justify mirror)
			)
		)
		(property "Dielectric" "X5R"
			(at 341.376002 68.325 0)
			(layer "B.Fab")
			(hide yes)
			(effects
				(font
					(size 1 1)
					(thickness 0.15)
				)
				(justify mirror)
			)
		)
		(property "License" "Apache-2.0"
			(at 341.376002 68.325 0)
			(layer "B.Fab")
			(hide yes)
			(effects
				(font
					(size 1 1)
					(thickness 0.15)
				)
				(justify mirror)
			)
		)
		(property "MPN" "GRM155R61H104KE14D"
			(at 341.376002 68.325 0)
			(layer "B.Fab")
			(hide yes)
			(effects
				(font
					(size 1 1)
					(thickness 0.15)
				)
				(justify mirror)
			)
		)
		(property "Manufacturer" "Murata"
			(at 341.376002 68.325 0)
			(layer "B.Fab")
			(hide yes)
			(effects
				(font
					(size 1 1)
					(thickness 0.15)
				)
				(justify mirror)
			)
		)
		(property "Val" "100n"
			(at 341.376002 68.325 0)
			(layer "B.Fab")
			(hide yes)
			(effects
				(font
					(size 1 1)
					(thickness 0.15)
				)
				(justify mirror)
			)
		)
		(property "Voltage" "50V"
			(at 341.376002 68.325 0)
			(layer "B.Fab")
			(hide yes)
			(effects
				(font
					(size 1 1)
					(thickness 0.15)
				)
				(justify mirror)
			)
		)
		(sheetname "/FPGA MGT Interface/")
		(sheetfile "fpga-mgt.kicad_sch")
		(attr smd)
		(fp_rect
			(start -0.9659 0.481258)
			(end 0.9649 -0.458742)
			(stroke
				(width 0.05)
				(type solid)
			)
			(fill no)
			(layer "B.CrtYd")
		)
		(fp_line
			(start 0.499 -0.248)
			(end -0.499 -0.248)
			(stroke
				(width 0.15)
				(type solid)
			)
			(layer "B.Fab")
		)
		(fp_line
			(start -0.499 -0.248)
			(end -0.499 0.25)
			(stroke
				(width 0.15)
				(type solid)
			)
			(layer "B.Fab")
		)
		(fp_line
			(start 0.499 0.25)
			(end 0.499 -0.248)
			(stroke
				(width 0.15)
				(type solid)
			)
			(layer "B.Fab")
		)
		(fp_line
			(start -0.499 0.25)
			(end 0.499 0.25)
			(stroke
				(width 0.15)
				(type solid)
			)
			(layer "B.Fab")
		)
		(pad "1" smd roundrect
			(at -0.484 0 90)
			(size 0.59 0.64)
			(layers "B.Cu" "B.Mask" "B.Paste")
			(roundrect_rratio 0.25)
			(net 20 "/FPGA MGT Interface/PCIE.TXD1_P")
			(pintype "passive")
		)
		(pad "2" smd roundrect
			(at 0.484 0 90)
			(size 0.59 0.64)
			(layers "B.Cu" "B.Mask" "B.Paste")
			(roundrect_rratio 0.25)
			(net 21 "/FPGA MGT Interface/GTX_TX2_P")
			(pintype "passive")
		)
	)
)
